# BASEBOARD_FAB2 (Tioga Pass) — schematic netlist excerpt (pin names and nets, part order shuffled) for the footprints in the layout excerpt that follows; sources: Cadence DE-HDL packaged netlist, KiCad conversion of Wiwynn_Tioga_Pass_MB.brd

C2D42  CAP_A  22.0UF 4V 20% X6S  pkg 0603V  page 225 : A = PVDDQ_GHJ ; B = GND
C5D40  CAP_A  22.0UF 4V 20% X6S  pkg 0603V  page 42 : A = PVCCIN_CPU0 ; B = GND
C5G17  CAP_A  47UF 4V 20% X5R  pkg 0603V  page 217 : A = PVDDQ_ABC ; B = GND

(kicad_pcb
	(version 20260206)
	(generator "pcbnew")
	(generator_version "10.0")
	(general
		(thickness 1.6)
		(legacy_teardrops no)
	)
	(paper "A4")
	(title_block
		(title "Wiwynn_Tioga_Pass_MB.brd")
		(comment 1 "Tioga Pass / footprints 1932-1934 of 4770")
	)
	(layers
		(0 "F.Cu" signal "TOP")
		(4 "In1.Cu" signal "L2GND")
		(6 "In2.Cu" signal "L3")
		(8 "In3.Cu" signal "L4GND")
		(10 "In4.Cu" signal "L5")
		(12 "In5.Cu" signal "L6GND")
		(14 "In6.Cu" signal "L7VCC")
		(16 "In7.Cu" signal "L8VCC")
		(18 "In8.Cu" signal "L9GND")
		(20 "In9.Cu" signal "L10")
		(22 "In10.Cu" signal "L11GND")
		(24 "In11.Cu" signal "L12")
		(26 "In12.Cu" signal "L13GND")
		(2 "B.Cu" signal "BOTTOM")
		(9 "F.Adhes" user "F.Adhesive")
		(11 "B.Adhes" user "B.Adhesive")
		(13 "F.Paste" user "Package Geometry/Pastemask Top")
		(15 "B.Paste" user "Package Geometry/Pastemask Bottom")
		(5 "F.SilkS" user "Ref Des/Silkscreen Top")
		(7 "B.SilkS" user "Ref Des/Silkscreen Bottom")
		(1 "F.Mask" user "Board Geometry/Soldermask Top")
		(3 "B.Mask" user "Board Geometry/Soldermask Bottom")
		(17 "Dwgs.User" user "User.Drawings")
		(19 "Cmts.User" user "User.Comments")
		(21 "Eco1.User" user "User.Eco1")
		(23 "Eco2.User" user "User.Eco2")
		(25 "Edge.Cuts" user "Board Geometry/Outline")
		(27 "Margin" user)
		(31 "F.CrtYd" user "Package Geometry/Place Bound Top")
		(29 "B.CrtYd" user "Package Geometry/Place Bound Bottom")
		(35 "F.Fab" user "Ref Des/Assembly Top")
		(33 "B.Fab" user "Ref Des/Assembly Bottom")
	)
	(footprint ""
		(layer "F.Cu")
		(at 99.455224 -68.641214 -90)
		(property "Reference" "C2D42"
			(at 0 0 270)
			(layer "F.SilkS")
			(hide yes)
			(effects
				(font
					(size 1.27 1.27)
				)
			)
		)
		(property "Value" ""
			(at 0 0 270)
			(layer "F.Fab")
			(effects
				(font
					(size 1.27 1.27)
				)
			)
		)
		(duplicate_pad_numbers_are_jumpers no)
		(fp_poly
			(pts
				(xy -0.4953 -0.2032) (xy 0.4953 -0.2032) (xy 0.4953 1.6002) (xy -0.4953 1.6002)
			)
			(stroke
				(width 0)
				(type default)
			)
			(fill no)
			(layer "F.CrtYd")
		)
		(fp_line
			(start -0.4953 1.6002)
			(end -0.4953 -0.2032)
			(stroke
				(width 0.1)
				(type default)
			)
			(layer "F.Fab")
		)
		(fp_line
			(start 0.4953 1.6002)
			(end -0.4953 1.6002)
			(stroke
				(width 0.1)
				(type default)
			)
			(layer "F.Fab")
		)
		(fp_line
			(start -0.4953 -0.2032)
			(end 0.4953 -0.2032)
			(stroke
				(width 0.1)
				(type default)
			)
			(layer "F.Fab")
		)
		(fp_line
			(start 0.4953 -0.2032)
			(end 0.4953 1.6002)
			(stroke
				(width 0.1)
				(type default)
			)
			(layer "F.Fab")
		)
		(pad "1" smd rect
			(at 0 0 270)
			(size 0.762 0.889)
			(layers "F.Cu" "F.Mask" "F.Paste")
			(net "PVDDQ_GHJ")
		)
		(pad "2" smd rect
			(at 0 1.397 270)
			(size 0.762 0.889)
			(layers "F.Cu" "F.Mask" "F.Paste")
			(net "GND")
		)
		(zone
			(layer "F.Cu")
			(hatch none 0.5)
			(connect_pads
				(clearance 0)
			)
			(min_thickness 0.25)
			(keepout
				(tracks not_allowed)
				(vias allowed)
				(pads allowed)
				(copperpour not_allowed)
				(footprints allowed)
			)
			(placement
				(enabled no)
				(sheetname "")
			)
			(fill
				(thermal_gap 0.5)
				(thermal_bridge_width 0.5)
				(island_removal_mode 0)
			)
			(polygon
				(pts
					(xy 99.010724 -69.022214) (xy 99.010724 -68.260214) (xy 98.502724 -68.260214) (xy 98.502724 -69.022214)
				)
			)
		)
	)
	(footprint ""
		(layer "F.Cu")
		(at 259.452872 -73.318116)
		(property "Reference" "C5D40"
			(at 0 0 0)
			(layer "F.SilkS")
			(hide yes)
			(effects
				(font
					(size 1.27 1.27)
				)
			)
		)
		(property "Value" ""
			(at 0 0 0)
			(layer "F.Fab")
			(effects
				(font
					(size 1.27 1.27)
				)
			)
		)
		(duplicate_pad_numbers_are_jumpers no)
		(fp_poly
			(pts
				(xy -0.4953 -0.2032) (xy 0.4953 -0.2032) (xy 0.4953 1.6002) (xy -0.4953 1.6002)
			)
			(stroke
				(width 0)
				(type default)
			)
			(fill no)
			(layer "F.CrtYd")
		)
		(fp_line
			(start -0.4953 -0.2032)
			(end 0.4953 -0.2032)
			(stroke
				(width 0.1)
				(type default)
			)
			(layer "F.Fab")
		)
		(fp_line
			(start -0.4953 1.6002)
			(end -0.4953 -0.2032)
			(stroke
				(width 0.1)
				(type default)
			)
			(layer "F.Fab")
		)
		(fp_line
			(start 0.4953 -0.2032)
			(end 0.4953 1.6002)
			(stroke
				(width 0.1)
				(type default)
			)
			(layer "F.Fab")
		)
		(fp_line
			(start 0.4953 1.6002)
			(end -0.4953 1.6002)
			(stroke
				(width 0.1)
				(type default)
			)
			(layer "F.Fab")
		)
		(pad "1" smd rect
			(at 0 0)
			(size 0.762 0.889)
			(layers "F.Cu" "F.Mask" "F.Paste")
			(net "PVCCIN_CPU0")
		)
		(pad "2" smd rect
			(at 0 1.397)
			(size 0.762 0.889)
			(layers "F.Cu" "F.Mask" "F.Paste")
			(net "GND")
		)
		(zone
			(layer "F.Cu")
			(hatch none 0.5)
			(connect_pads
				(clearance 0)
			)
			(min_thickness 0.25)
			(keepout
				(tracks not_allowed)
				(vias allowed)
				(pads allowed)
				(copperpour not_allowed)
				(footprints allowed)
			)
			(placement
				(enabled no)
				(sheetname "")
			)
			(fill
				(thermal_gap 0.5)
				(thermal_bridge_width 0.5)
				(island_removal_mode 0)
			)
			(polygon
				(pts
					(xy 259.071872 -72.873616) (xy 259.833872 -72.873616) (xy 259.833872 -72.365616) (xy 259.071872 -72.365616)
				)
			)
		)
	)
	(footprint ""
		(layer "F.Cu")
		(at 272.861532 -3.3528 90)
		(property "Reference" "C5G17"
			(at 1.848866 0.752348 90)
			(unlocked yes)
			(layer "F.SilkS")
			(effects
				(font
					(size 1.27 0.9652)
					(thickness 0.1524)
				)
			)
		)
		(property "Value" ""
			(at 0 0 90)
			(layer "F.Fab")
			(effects
				(font
					(size 1.27 1.27)
				)
			)
		)
		(duplicate_pad_numbers_are_jumpers no)
		(fp_rect
			(start -0.500126 1.598422)
			(end 0.500126 -0.201422)
			(stroke
				(width 0)
				(type default)
			)
			(fill no)
			(layer "F.CrtYd")
		)
		(fp_line
			(start 0.500126 -0.201422)
			(end 0.500126 1.598422)
			(stroke
				(width 0.1)
				(type default)
			)
			(layer "F.Fab")
		)
		(fp_line
			(start -0.500126 -0.201422)
			(end 0.500126 -0.201422)
			(stroke
				(width 0.1)
				(type default)
			)
			(layer "F.Fab")
		)
		(fp_line
			(start 0.500126 1.598422)
			(end -0.500126 1.598422)
			(stroke
				(width 0.1)
				(type default)
			)
			(layer "F.Fab")
		)
		(fp_line
			(start -0.500126 1.598422)
			(end -0.500126 -0.201422)
			(stroke
				(width 0.1)
				(type default)
			)
			(layer "F.Fab")
		)
		(pad "1" smd rect
			(at 0 0)
			(size 0.889 0.9906)
			(layers "F.Cu" "F.Mask" "F.Paste")
			(net "PVDDQ_ABC")
		)
		(pad "2" smd rect
			(at 0 1.397)
			(size 0.889 0.9906)
			(layers "F.Cu" "F.Mask" "F.Paste")
			(net "GND")
		)
		(zone
			(layer "F.Cu")
			(hatch none 0.5)
			(connect_pads
				(clearance 0)
			)
			(min_thickness 0.25)
			(keepout
				(tracks allowed)
				(vias not_allowed)
				(pads allowed)
				(copperpour not_allowed)
				(footprints allowed)
			)
			(placement
				(enabled no)
				(sheetname "")
			)
			(fill
				(thermal_gap 0.5)
				(thermal_bridge_width 0.5)
				(island_removal_mode 0)
			)
			(polygon
				(pts
					(xy 273.814032 -2.8575) (xy 273.814032 -3.8481) (xy 273.306032 -3.8481) (xy 273.306032 -2.8575)
				)
			)
		)
		(zone
			(layer "F.Cu")
			(hatch none 0.5)
			(connect_pads
				(clearance 0)
			)
			(min_thickness 0.25)
			(keepout
				(tracks not_allowed)
				(vias allowed)
				(pads allowed)
				(copperpour not_allowed)
				(footprints allowed)
			)
			(placement
				(enabled no)
				(sheetname "")
			)
			(fill
				(thermal_gap 0.5)
				(thermal_bridge_width 0.5)
				(island_removal_mode 0)
			)
			(polygon
				(pts
					(xy 273.814032 -2.8575) (xy 273.814032 -3.8481) (xy 273.306032 -3.8481) (xy 273.306032 -2.8575)
				)
			)
		)
	)
)
